(kicad_pcb
	(version 20260206)
	(generator "pcbnew")
	(generator_version "10.0")
	(general
		(thickness 1.6)
		(legacy_teardrops no)
	)
	(paper "A4")
	(title_block
		(title "01162023_DA0F0TEBIF0_F0T_Expander_BD_F_brd_V02_OCP.brd")
		(comment 1 "Grand Teton / footprints 3178-3183 of 9728")
	)
	(layers
		(0 "F.Cu" signal "TOP")
		(4 "In1.Cu" signal "GND")
		(6 "In2.Cu" signal "VCC")
		(8 "In3.Cu" signal "VCC1")
		(10 "In4.Cu" signal "GND1")
		(12 "In5.Cu" signal "IN1")
		(14 "In6.Cu" signal "GND2")
		(16 "In7.Cu" signal "IN2")
		(18 "In8.Cu" signal "GND3")
		(20 "In9.Cu" signal "IN3")
		(22 "In10.Cu" signal "GND4")
		(24 "In11.Cu" signal "IN4")
		(26 "In12.Cu" signal "GND5")
		(28 "In13.Cu" signal "IN5")
		(30 "In14.Cu" signal "GND6")
		(32 "In15.Cu" signal "IN6")
		(34 "In16.Cu" signal "GND7")
		(2 "B.Cu" signal "BOTTOM")
		(9 "F.Adhes" user "F.Adhesive")
		(11 "B.Adhes" user "B.Adhesive")
		(13 "F.Paste" user "Package Geometry/Pastemask Top")
		(15 "B.Paste" user "Package Geometry/Pastemask Bottom")
		(5 "F.SilkS" user "Ref Des/Silkscreen Top")
		(7 "B.SilkS" user "Ref Des/Silkscreen Bottom")
		(1 "F.Mask" user "Board Geometry/Soldermask Top")
		(3 "B.Mask" user "Board Geometry/Soldermask Bottom")
		(17 "Dwgs.User" user "User.Drawings")
		(19 "Cmts.User" user "User.Comments")
		(21 "Eco1.User" user "User.Eco1")
		(23 "Eco2.User" user "User.Eco2")
		(25 "Edge.Cuts" user "Board Geometry/Outline")
		(27 "Margin" user)
		(31 "F.CrtYd" user "Package Geometry/Place Bound Top")
		(29 "B.CrtYd" user "Package Geometry/Place Bound Bottom")
		(35 "F.Fab" user "Ref Des/Assembly Top")
		(33 "B.Fab" user "Ref Des/Assembly Bottom")
	)
	(footprint ""
		(layer "F.Cu")
		(at 330.424028 -236.871256 -90)
		(property "Reference" "R1788"
			(at 0 0 270)
			(layer "F.SilkS")
			(hide yes)
			(effects
				(font
					(size 1.27 1.27)
				)
			)
		)
		(property "Value" ""
			(at 0 0 270)
			(layer "F.Fab")
			(effects
				(font
					(size 1.27 1.27)
				)
			)
		)
		(duplicate_pad_numbers_are_jumpers no)
		(fp_line
			(start -0.7874 0.4064)
			(end -0.7874 -0.4064)
			(stroke
				(width 0.1524)
				(type default)
			)
			(layer "F.SilkS")
		)
		(fp_line
			(start 0.7874 0.4064)
			(end -0.7874 0.4064)
			(stroke
				(width 0.1524)
				(type default)
			)
			(layer "F.SilkS")
		)
		(fp_line
			(start -0.7874 -0.4064)
			(end 0.7874 -0.4064)
			(stroke
				(width 0.1524)
				(type default)
			)
			(layer "F.SilkS")
		)
		(fp_line
			(start 0.7874 -0.4064)
			(end 0.7874 0.4064)
			(stroke
				(width 0.1524)
				(type default)
			)
			(layer "F.SilkS")
		)
		(fp_line
			(start -0.67945 0.3048)
			(end -0.67945 -0.305054)
			(stroke
				(width 0.1)
				(type default)
			)
			(layer "F.Fab")
		)
		(fp_line
			(start -0.12065 0.3048)
			(end -0.67945 0.3048)
			(stroke
				(width 0.1)
				(type default)
			)
			(layer "F.Fab")
		)
		(fp_line
			(start 0.120396 0.3048)
			(end 0.120396 0.2794)
			(stroke
				(width 0.1)
				(type default)
			)
			(layer "F.Fab")
		)
		(fp_line
			(start 0.67945 0.3048)
			(end 0.120396 0.3048)
			(stroke
				(width 0.1)
				(type default)
			)
			(layer "F.Fab")
		)
		(fp_line
			(start -0.12065 0.2794)
			(end -0.12065 0.3048)
			(stroke
				(width 0.1)
				(type default)
			)
			(layer "F.Fab")
		)
		(fp_line
			(start 0.120396 0.2794)
			(end -0.12065 0.2794)
			(stroke
				(width 0.1)
				(type default)
			)
			(layer "F.Fab")
		)
		(fp_line
			(start -0.12065 -0.2794)
			(end 0.12065 -0.2794)
			(stroke
				(width 0.1)
				(type default)
			)
			(layer "F.Fab")
		)
		(fp_line
			(start 0.12065 -0.2794)
			(end 0.12065 -0.3048)
			(stroke
				(width 0.1)
				(type default)
			)
			(layer "F.Fab")
		)
		(fp_line
			(start 0.12065 -0.3048)
			(end 0.67945 -0.3048)
			(stroke
				(width 0.1)
				(type default)
			)
			(layer "F.Fab")
		)
		(fp_line
			(start 0.67945 -0.3048)
			(end 0.67945 0.3048)
			(stroke
				(width 0.1)
				(type default)
			)
			(layer "F.Fab")
		)
		(fp_line
			(start -0.67945 -0.305054)
			(end -0.12065 -0.305054)
			(stroke
				(width 0.1)
				(type default)
			)
			(layer "F.Fab")
		)
		(fp_line
			(start -0.12065 -0.305054)
			(end -0.12065 -0.2794)
			(stroke
				(width 0.1)
				(type default)
			)
			(layer "F.Fab")
		)
		(pad "1" smd circle
			(at -0.40005 0 270)
			(size 0 0)
			(layers "F.Cu" "F.Mask" "F.Paste")
			(net "RST_MB_PERST_0_ISO_N")
		)
		(pad "2" smd circle
			(at 0.40005 0 270)
			(size 0 0)
			(layers "F.Cu" "F.Mask" "F.Paste")
			(net "RST_MB_PERST_0_ISO_R_N")
		)
	)
	(footprint ""
		(layer "F.Cu")
		(at 124.272548 -356.244906 90)
		(property "Reference" "C352"
			(at 0 0 90)
			(layer "F.SilkS")
			(hide yes)
			(effects
				(font
					(size 1.27 1.27)
				)
			)
		)
		(property "Value" ""
			(at 0 0 90)
			(layer "F.Fab")
			(effects
				(font
					(size 1.27 1.27)
				)
			)
		)
		(duplicate_pad_numbers_are_jumpers no)
		(fp_line
			(start 0.299974 -0.150114)
			(end 0.299974 0.150114)
			(stroke
				(width 0.1)
				(type default)
			)
			(layer "F.Fab")
		)
		(fp_line
			(start -0.299974 -0.150114)
			(end 0.299974 -0.150114)
			(stroke
				(width 0.1)
				(type default)
			)
			(layer "F.Fab")
		)
		(fp_line
			(start 0.299974 0.150114)
			(end -0.299974 0.150114)
			(stroke
				(width 0.1)
				(type default)
			)
			(layer "F.Fab")
		)
		(fp_line
			(start -0.299974 0.150114)
			(end -0.299974 -0.150114)
			(stroke
				(width 0.1)
				(type default)
			)
			(layer "F.Fab")
		)
		(pad "1" smd rect
			(at -0.2667 0 90)
			(size 0.3048 0.381)
			(layers "F.Cu" "F.Mask" "F.Paste")
			(net "P5E_PEX1_STN6_TX_DP<105>")
		)
		(pad "2" smd rect
			(at 0.2667 0 90)
			(size 0.3048 0.381)
			(layers "F.Cu" "F.Mask" "F.Paste")
			(net "P5E_PEX1_STN6_TX_C_DP<105>")
		)
	)
	(footprint ""
		(layer "F.Cu")
		(at 176.311052 -61.386974)
		(property "Reference" "R4490"
			(at 0 0 0)
			(layer "F.SilkS")
			(hide yes)
			(effects
				(font
					(size 1.27 1.27)
				)
			)
		)
		(property "Value" ""
			(at 0 0 0)
			(layer "F.Fab")
			(effects
				(font
					(size 1.27 1.27)
				)
			)
		)
		(duplicate_pad_numbers_are_jumpers no)
		(fp_line
			(start -0.7874 -0.4064)
			(end 0.7874 -0.4064)
			(stroke
				(width 0.1524)
				(type default)
			)
			(layer "F.SilkS")
		)
		(fp_line
			(start -0.7874 0.4064)
			(end -0.7874 -0.4064)
			(stroke
				(width 0.1524)
				(type default)
			)
			(layer "F.SilkS")
		)
		(fp_line
			(start 0.7874 -0.4064)
			(end 0.7874 0.4064)
			(stroke
				(width 0.1524)
				(type default)
			)
			(layer "F.SilkS")
		)
		(fp_line
			(start 0.7874 0.4064)
			(end -0.7874 0.4064)
			(stroke
				(width 0.1524)
				(type default)
			)
			(layer "F.SilkS")
		)
		(fp_line
			(start -0.67945 -0.305054)
			(end -0.12065 -0.305054)
			(stroke
				(width 0.1)
				(type default)
			)
			(layer "F.Fab")
		)
		(fp_line
			(start -0.67945 0.3048)
			(end -0.67945 -0.305054)
			(stroke
				(width 0.1)
				(type default)
			)
			(layer "F.Fab")
		)
		(fp_line
			(start -0.12065 -0.305054)
			(end -0.12065 -0.2794)
			(stroke
				(width 0.1)
				(type default)
			)
			(layer "F.Fab")
		)
		(fp_line
			(start -0.12065 -0.2794)
			(end 0.12065 -0.2794)
			(stroke
				(width 0.1)
				(type default)
			)
			(layer "F.Fab")
		)
		(fp_line
			(start -0.12065 0.2794)
			(end -0.12065 0.3048)
			(stroke
				(width 0.1)
				(type default)
			)
			(layer "F.Fab")
		)
		(fp_line
			(start -0.12065 0.3048)
			(end -0.67945 0.3048)
			(stroke
				(width 0.1)
				(type default)
			)
			(layer "F.Fab")
		)
		(fp_line
			(start 0.120396 0.2794)
			(end -0.12065 0.2794)
			(stroke
				(width 0.1)
				(type default)
			)
			(layer "F.Fab")
		)
		(fp_line
			(start 0.120396 0.3048)
			(end 0.120396 0.2794)
			(stroke
				(width 0.1)
				(type default)
			)
			(layer "F.Fab")
		)
		(fp_line
			(start 0.12065 -0.3048)
			(end 0.67945 -0.3048)
			(stroke
				(width 0.1)
				(type default)
			)
			(layer "F.Fab")
		)
		(fp_line
			(start 0.12065 -0.2794)
			(end 0.12065 -0.3048)
			(stroke
				(width 0.1)
				(type default)
			)
			(layer "F.Fab")
		)
		(fp_line
			(start 0.67945 -0.3048)
			(end 0.67945 0.3048)
			(stroke
				(width 0.1)
				(type default)
			)
			(layer "F.Fab")
		)
		(fp_line
			(start 0.67945 0.3048)
			(end 0.120396 0.3048)
			(stroke
				(width 0.1)
				(type default)
			)
			(layer "F.Fab")
		)
		(pad "1" smd circle
			(at -0.40005 0)
			(size 0 0)
			(layers "F.Cu" "F.Mask" "F.Paste")
			(net "PWRGD_P3V3_SSD6")
		)
		(pad "2" smd circle
			(at 0.40005 0)
			(size 0 0)
			(layers "F.Cu" "F.Mask" "F.Paste")
			(net "PWRGD_P3V3_SSD6_R")
		)
	)
	(footprint ""
		(layer "F.Cu")
		(at 105.7783 -222.706692)
		(property "Reference" "PU20"
			(at -1.340612 5.197094 90)
			(unlocked yes)
			(layer "F.SilkS")
			(effects
				(font
					(size 0.7874 0.5842)
					(thickness 0.1524)
				)
				(justify left)
			)
		)
		(property "Value" ""
			(at 0 0 0)
			(layer "F.Fab")
			(effects
				(font
					(size 1.27 1.27)
				)
			)
		)
		(duplicate_pad_numbers_are_jumpers no)
		(fp_line
			(start -1.9812 0)
			(end -2.3622 0)
			(stroke
				(width 0.1524)
				(type default)
			)
			(layer "F.SilkS")
		)
		(fp_line
			(start -1.549908 -2.050034)
			(end -1.549908 -1.9812)
			(stroke
				(width 0.1524)
				(type default)
			)
			(layer "F.SilkS")
		)
		(fp_line
			(start -1.549908 1.9812)
			(end -1.549908 2.050034)
			(stroke
				(width 0.1524)
				(type default)
			)
			(layer "F.SilkS")
		)
		(fp_line
			(start -1.549908 2.050034)
			(end -0.5842 2.050034)
			(stroke
				(width 0.1524)
				(type default)
			)
			(layer "F.SilkS")
		)
		(fp_line
			(start -0.5842 -2.050034)
			(end -1.549908 -2.050034)
			(stroke
				(width 0.1524)
				(type default)
			)
			(layer "F.SilkS")
		)
		(fp_line
			(start -0.3048 2.4638)
			(end -0.3048 3.2258)
			(stroke
				(width 0.1524)
				(type default)
			)
			(layer "F.SilkS")
		)
		(fp_line
			(start 0 2.050034)
			(end 1.549908 2.050034)
			(stroke
				(width 0.1524)
				(type default)
			)
			(layer "F.SilkS")
		)
		(fp_line
			(start 0.3048 -2.4638)
			(end 0.3048 -3.2258)
			(stroke
				(width 0.1524)
				(type default)
			)
			(layer "F.SilkS")
		)
		(fp_line
			(start 1.549908 -2.050034)
			(end 0.5842 -2.050034)
			(stroke
				(width 0.1524)
				(type default)
			)
			(layer "F.SilkS")
		)
		(fp_line
			(start 1.549908 -1.9812)
			(end 1.549908 -2.050034)
			(stroke
				(width 0.1524)
				(type default)
			)
			(layer "F.SilkS")
		)
		(fp_line
			(start 1.549908 2.050034)
			(end 1.549908 1.9304)
			(stroke
				(width 0.1524)
				(type default)
			)
			(layer "F.SilkS")
		)
		(fp_poly
			(pts
				(xy -2.9464 -2.208022) (xy -2.9464 -1.192022) (xy -1.9304 -1.700022)
			)
			(stroke
				(width 0)
				(type default)
			)
			(fill yes)
			(layer "F.SilkS")
		)
		(fp_line
			(start -1.9812 0)
			(end -2.3622 0)
			(stroke
				(width 0.1)
				(type default)
			)
			(layer "F.Fab")
		)
		(fp_line
			(start -1.549908 -2.050034)
			(end -1.549908 2.050034)
			(stroke
				(width 0.1)
				(type default)
			)
			(layer "F.Fab")
		)
		(fp_line
			(start -1.549908 2.050034)
			(end 1.549908 2.050034)
			(stroke
				(width 0.1)
				(type default)
			)
			(layer "F.Fab")
		)
		(fp_line
			(start -0.3048 2.4638)
			(end -0.3048 3.2258)
			(stroke
				(width 0.1)
				(type default)
			)
			(layer "F.Fab")
		)
		(fp_line
			(start 0.3048 -2.4638)
			(end 0.3048 -3.2258)
			(stroke
				(width 0.1)
				(type default)
			)
			(layer "F.Fab")
		)
		(fp_line
			(start 1.549908 -2.050034)
			(end -1.549908 -2.050034)
			(stroke
				(width 0.1)
				(type default)
			)
			(layer "F.Fab")
		)
		(fp_line
			(start 1.549908 2.050034)
			(end 1.549908 -2.050034)
			(stroke
				(width 0.1)
				(type default)
			)
			(layer "F.Fab")
		)
		(fp_poly
			(pts
				(xy -2.9464 -2.208022) (xy -2.9464 -1.192022) (xy -1.9304 -1.700022)
			)
			(stroke
				(width 0)
				(type default)
			)
			(fill yes)
			(layer "F.Fab")
		)
		(fp_text user "9"
			(at -2.338832 2.0574 270)
			(unlocked yes)
			(layer "F.SilkS")
			(effects
				(font
					(size 0.635 0.4064)
					(thickness 0.1524)
				)
			)
		)
		(fp_text user "19"
			(at 1.89865 -2.616708 270)
			(unlocked yes)
			(layer "F.SilkS")
			(effects
				(font
					(size 0.635 0.4064)
					(thickness 0.1524)
				)
			)
		)
		(fp_text user "11_18"
			(at 2.512568 0.9906 270)
			(unlocked yes)
			(layer "F.SilkS")
			(effects
				(font
					(size 0.635 0.4064)
					(thickness 0.1524)
				)
			)
		)
		(fp_text user "9"
			(at -2.338832 2.0574 270)
			(unlocked yes)
			(layer "F.Fab")
			(effects
				(font
					(size 0.635 0.4064)
					(thickness 0.1524)
				)
			)
		)
		(fp_text user "19"
			(at 2.410968 -2.159 270)
			(unlocked yes)
			(layer "F.Fab")
			(effects
				(font
					(size 0.635 0.4064)
					(thickness 0.1524)
				)
			)
		)
		(fp_text user "11_18"
			(at 2.512568 0.9906 270)
			(unlocked yes)
			(layer "F.Fab")
			(effects
				(font
					(size 0.635 0.4064)
					(thickness 0.1524)
				)
			)
		)
		(pad "1" smd rect
			(at -1.35001 -1.700022 90)
			(size 0.3048 0.9144)
			(layers "F.Cu" "F.Mask" "F.Paste")
			(net "SW_P1V8_PEX_BT")
		)
		(pad "2" smd rect
			(at -1.400048 -1.199896 90)
			(size 0.1778 0.8128)
			(layers "F.Cu" "F.Mask" "F.Paste")
			(net "GND")
		)
		(pad "3" smd rect
			(at -1.400048 -0.8001 90)
			(size 0.1778 0.8128)
			(layers "F.Cu" "F.Mask" "F.Paste")
			(net "P1V8_PEX_CS")
		)
		(pad "4" smd rect
			(at -1.400048 -0.40005 90)
			(size 0.1778 0.8128)
			(layers "F.Cu" "F.Mask" "F.Paste")
			(net "GND")
		)
		(pad "5" smd rect
			(at -1.400048 0 90)
			(size 0.1778 0.8128)
			(layers "F.Cu" "F.Mask" "F.Paste")
			(net "P1V8_PEX_REF")
		)
		(pad "6" smd rect
			(at -1.400048 0.40005 90)
			(size 0.1778 0.8128)
			(layers "F.Cu" "F.Mask" "F.Paste")
			(net "GND")
		)
		(pad "7" smd rect
			(at -1.400048 0.8001 90)
			(size 0.1778 0.8128)
			(layers "F.Cu" "F.Mask" "F.Paste")
			(net "P1V8_PEX_FB")
		)
		(pad "8" smd rect
			(at -1.400048 1.199896 90)
			(size 0.1778 0.8128)
			(layers "F.Cu" "F.Mask" "F.Paste")
			(net "P1V8_PEX_EN")
		)
		(pad "9" smd rect
			(at -1.400048 1.700022 90)
			(size 0.3048 0.8128)
			(layers "F.Cu" "F.Mask" "F.Paste")
			(net "PWRGD_P1V8_PEX")
		)
		(pad "10" smd rect
			(at -0.299974 1.299972)
			(size 0.3048 2.0066)
			(layers "F.Cu" "F.Mask" "F.Paste")
			(net "SW_P12V_P1V8_PEX_FLT")
		)
		(pad "11_18" smd circle
			(at 1.175004 0.275082)
			(size 0 0)
			(layers "F.Cu" "F.Mask" "F.Paste")
			(net "GND")
		)
		(pad "19" smd rect
			(at 1.400048 -1.700022 270)
			(size 0.3048 0.8128)
			(layers "F.Cu" "F.Mask" "F.Paste")
			(net "P1V8_PEX_VCC")
		)
		(pad "20" smd rect
			(at 0.299974 -1.299972)
			(size 0.3048 2.0066)
			(layers "F.Cu" "F.Mask" "F.Paste")
			(net "SW_P1V8_PEX_PH")
		)
		(pad "21" smd rect
			(at -0.299974 -1.299972)
			(size 0.3048 2.0066)
			(layers "F.Cu" "F.Mask" "F.Paste")
			(net "SW_P12V_P1V8_PEX_FLT")
		)
	)
	(footprint ""
		(layer "F.Cu")
		(at 197.702932 -414.452054 90)
		(property "Reference" "R6781"
			(at 0 0 90)
			(layer "F.SilkS")
			(hide yes)
			(effects
				(font
					(size 1.27 1.27)
				)
			)
		)
		(property "Value" ""
			(at 0 0 90)
			(layer "F.Fab")
			(effects
				(font
					(size 1.27 1.27)
				)
			)
		)
		(duplicate_pad_numbers_are_jumpers no)
		(fp_line
			(start 0.7874 -0.4064)
			(end 0.7874 0.4064)
			(stroke
				(width 0.1524)
				(type default)
			)
			(layer "F.SilkS")
		)
		(fp_line
			(start -0.7874 -0.4064)
			(end 0.7874 -0.4064)
			(stroke
				(width 0.1524)
				(type default)
			)
			(layer "F.SilkS")
		)
		(fp_line
			(start 0.7874 0.4064)
			(end -0.7874 0.4064)
			(stroke
				(width 0.1524)
				(type default)
			)
			(layer "F.SilkS")
		)
		(fp_line
			(start -0.7874 0.4064)
			(end -0.7874 -0.4064)
			(stroke
				(width 0.1524)
				(type default)
			)
			(layer "F.SilkS")
		)
		(fp_line
			(start -0.12065 -0.305054)
			(end -0.12065 -0.2794)
			(stroke
				(width 0.1)
				(type default)
			)
			(layer "F.Fab")
		)
		(fp_line
			(start -0.67945 -0.305054)
			(end -0.12065 -0.305054)
			(stroke
				(width 0.1)
				(type default)
			)
			(layer "F.Fab")
		)
		(fp_line
			(start 0.67945 -0.3048)
			(end 0.67945 0.3048)
			(stroke
				(width 0.1)
				(type default)
			)
			(layer "F.Fab")
		)
		(fp_line
			(start 0.12065 -0.3048)
			(end 0.67945 -0.3048)
			(stroke
				(width 0.1)
				(type default)
			)
			(layer "F.Fab")
		)
		(fp_line
			(start 0.12065 -0.2794)
			(end 0.12065 -0.3048)
			(stroke
				(width 0.1)
				(type default)
			)
			(layer "F.Fab")
		)
		(fp_line
			(start -0.12065 -0.2794)
			(end 0.12065 -0.2794)
			(stroke
				(width 0.1)
				(type default)
			)
			(layer "F.Fab")
		)
		(fp_line
			(start 0.120396 0.2794)
			(end -0.12065 0.2794)
			(stroke
				(width 0.1)
				(type default)
			)
			(layer "F.Fab")
		)
		(fp_line
			(start -0.12065 0.2794)
			(end -0.12065 0.3048)
			(stroke
				(width 0.1)
				(type default)
			)
			(layer "F.Fab")
		)
		(fp_line
			(start 0.67945 0.3048)
			(end 0.120396 0.3048)
			(stroke
				(width 0.1)
				(type default)
			)
			(layer "F.Fab")
		)
		(fp_line
			(start 0.120396 0.3048)
			(end 0.120396 0.2794)
			(stroke
				(width 0.1)
				(type default)
			)
			(layer "F.Fab")
		)
		(fp_line
			(start -0.12065 0.3048)
			(end -0.67945 0.3048)
			(stroke
				(width 0.1)
				(type default)
			)
			(layer "F.Fab")
		)
		(fp_line
			(start -0.67945 0.3048)
			(end -0.67945 -0.305054)
			(stroke
				(width 0.1)
				(type default)
			)
			(layer "F.Fab")
		)
		(pad "1" smd circle
			(at -0.40005 0 90)
			(size 0 0)
			(layers "F.Cu" "F.Mask" "F.Paste")
			(net "P3V3_AUX")
		)
		(pad "2" smd circle
			(at 0.40005 0 90)
			(size 0 0)
			(layers "F.Cu" "F.Mask" "F.Paste")
			(net "UV_P2V5_COMP")
		)
	)
	(footprint ""
		(layer "F.Cu")
		(at 118.969028 -343.952322 90)
		(property "Reference" "C345"
			(at 0 0 90)
			(layer "F.SilkS")
			(hide yes)
			(effects
				(font
					(size 1.27 1.27)
				)
			)
		)
		(property "Value" ""
			(at 0 0 90)
			(layer "F.Fab")
			(effects
				(font
					(size 1.27 1.27)
				)
			)
		)
		(duplicate_pad_numbers_are_jumpers no)
		(fp_line
			(start 0.299974 -0.150114)
			(end 0.299974 0.150114)
			(stroke
				(width 0.1)
				(type default)
			)
			(layer "F.Fab")
		)
		(fp_line
			(start -0.299974 -0.150114)
			(end 0.299974 -0.150114)
			(stroke
				(width 0.1)
				(type default)
			)
			(layer "F.Fab")
		)
		(fp_line
			(start 0.299974 0.150114)
			(end -0.299974 0.150114)
			(stroke
				(width 0.1)
				(type default)
			)
			(layer "F.Fab")
		)
		(fp_line
			(start -0.299974 0.150114)
			(end -0.299974 -0.150114)
			(stroke
				(width 0.1)
				(type default)
			)
			(layer "F.Fab")
		)
		(pad "1" smd rect
			(at -0.2667 0 90)
			(size 0.3048 0.381)
			(layers "F.Cu" "F.Mask" "F.Paste")
			(net "P5E_PEX1_STN6_TX_DN<109>")
		)
		(pad "2" smd rect
			(at 0.2667 0 90)
			(size 0.3048 0.381)
			(layers "F.Cu" "F.Mask" "F.Paste")
			(net "P5E_PEX1_STN6_TX_C_DN<109>")
		)
	)
)
